#ISCELL
  mstr_misc dns *
  *
#ISCELL
  mstr_symbols cad_note *
  *
#ISCELL
  mstr_symbols intel_corp_bpage *
  *
#CELL
  mstr_discrete res *
  page145_i10
#CELL
  mstr_discrete res *
  page145_i100
#CELL
  mstr_discrete res *
  page145_i101
#ISCELL
  mstr_symbols gnd *
  page145_i102
#ISCELL
  mstr_standard offpage *
  page145_i103
#ISCELL
  mstr_standard offpage *
  page145_i104
#CELL
  mstr_discrete res *
  page145_i11
#CELL
  w_hdl ast2520a1-gp-gp *
  page145_i117
#CELL
  w_hdl 200r2f-l1-gp *
  page145_i118
#CELL
  mstr_discrete res *
  page145_i119
#ISCELL
  mstr_standard offpage *
  page145_i12
#CELL
  mstr_discrete res *
  page145_i120
#ISCELL
  mstr_standard offpage *
  page145_i121
#ISCELL
  mstr_standard offpage *
  page145_i122
#ISCELL
  mstr_standard offpage *
  page145_i123
#ISCELL
  mstr_standard offpage *
  page145_i124
#ISCELL
  mstr_standard offpage *
  page145_i128
#ISCELL
  mstr_symbols gnd *
  page145_i13
#CELL
  mstr_discrete res *
  page145_i136
#ISCELL
  mstr_standard offpage *
  page145_i137
#ISCELL
  mstr_standard offpage *
  page145_i138
#ISCELL
  mstr_standard offpage *
  page145_i139
#CELL
  mstr_discrete res *
  page145_i14
#ISCELL
  mstr_standard offpage *
  page145_i140
#ISCELL
  mstr_standard offpage *
  page145_i143
#ISCELL
  mstr_standard offpage *
  page145_i146
#ISCELL
  mstr_standard offpage *
  page145_i147
#CELL
  dev_discrete cap_a *
  page145_i15
#ISCELL
  mstr_standard offpage *
  page145_i154
#ISCELL
  mstr_standard offpage *
  page145_i155
#CELL
  dev_discrete cap_a *
  page145_i158
#CELL
  dev_discrete cap_a *
  page145_i159
#ISCELL
  mstr_symbols p3v3_stby *
  page145_i16
#CELL
  mstr_discrete res *
  page145_i160
#ISCELL
  mstr_standard offpage *
  page145_i161
#ISCELL
  mstr_standard offpage *
  page145_i162
#CELL
  mstr_discrete res *
  page145_i163
#CELL
  mstr_discrete res *
  page145_i164
#ISCELL
  mstr_standard offpage *
  page145_i165
#ISCELL
  mstr_standard offpage *
  page145_i166
#ISCELL
  mstr_standard offpage *
  page145_i167
#ISCELL
  mstr_standard offpage *
  page145_i168
#ISCELL
  mstr_standard offpage *
  page145_i169
#ISCELL
  mstr_symbols gnd *
  page145_i17
#ISCELL
  mstr_standard offpage *
  page145_i170
#ISCELL
  mstr_standard offpage *
  page145_i172
#CELL
  mstr_discrete res *
  page145_i173
#ISCELL
  mstr_standard offpage *
  page145_i174
#CELL
  mstr_discrete res *
  page145_i175
#CELL
  mstr_discrete res *
  page145_i176
#ISCELL
  mstr_standard offpage *
  page145_i177
#CELL
  mstr_discrete res *
  page145_i20
#ISCELL
  mstr_standard offpage *
  page145_i21
#CELL
  mstr_discrete res *
  page145_i22
#ISCELL
  mstr_symbols gnd *
  page145_i23
#ISCELL
  mstr_standard offpage *
  page145_i24
#ISCELL
  mstr_standard offpage *
  page145_i25
#ISCELL
  mstr_standard offpage *
  page145_i26
#ISCELL
  mstr_standard offpage *
  page145_i27
#ISCELL
  mstr_standard offpage *
  page145_i28
#ISCELL
  mstr_standard offpage *
  page145_i29
#CELL
  mstr_discrete res *
  page145_i30
#CELL
  mstr_discrete res *
  page145_i31
#ISCELL
  mstr_symbols gnd *
  page145_i32
#ISCELL
  mstr_symbols gnd *
  page145_i33
#CELL
  mstr_discrete res *
  page145_i34
#ISCELL
  mstr_symbols gnd *
  page145_i35
#CELL
  mstr_discrete res *
  page145_i36
#ISCELL
  mstr_symbols gnd *
  page145_i37
#CELL
  mstr_discrete res *
  page145_i38
#ISCELL
  mstr_symbols gnd *
  page145_i39
#ISCELL
  mstr_standard offpage *
  page145_i4
#ISCELL
  mstr_standard offpage *
  page145_i41
#ISCELL
  mstr_standard offpage *
  page145_i42
#ISCELL
  mstr_standard offpage *
  page145_i43
#ISCELL
  mstr_symbols gnd *
  page145_i47
#ISCELL
  mstr_standard offpage *
  page145_i48
#ISCELL
  mstr_standard offpage *
  page145_i49
#ISCELL
  mstr_standard offpage *
  page145_i51
#ISCELL
  mstr_standard offpage *
  page145_i52
#ISCELL
  mstr_standard offpage *
  page145_i53
#ISCELL
  mstr_standard offpage *
  page145_i54
#ISCELL
  mstr_standard offpage *
  page145_i55
#ISCELL
  mstr_standard offpage *
  page145_i56
#ISCELL
  mstr_standard offpage *
  page145_i57
#ISCELL
  mstr_standard offpage *
  page145_i58
#ISCELL
  mstr_standard offpage *
  page145_i59
#ISCELL
  mstr_standard offpage *
  page145_i6
#ISCELL
  mstr_standard offpage *
  page145_i7
#ISCELL
  mstr_standard offpage *
  page145_i70
#ISCELL
  mstr_standard offpage *
  page145_i71
#ISCELL
  mstr_standard offpage *
  page145_i72
#ISCELL
  mstr_standard offpage *
  page145_i73
#ISCELL
  mstr_standard offpage *
  page145_i74
#ISCELL
  mstr_standard offpage *
  page145_i75
#CELL
  mstr_discrete osc_c *
  page145_i8
#ISCELL
  mstr_standard offpage *
  page145_i85
#ISCELL
  mstr_standard offpage *
  page145_i86
#ISCELL
  mstr_standard offpage *
  page145_i87
#ISCELL
  mstr_standard offpage *
  page145_i88
#ISCELL
  mstr_standard offpage *
  page145_i89
#ISCELL
  mstr_standard offpage *
  page145_i9
#ISCELL
  mstr_standard offpage *
  page145_i90
#ISCELL
  mstr_standard offpage *
  page145_i91
#ISCELL
  mstr_standard offpage *
  page145_i92
#ISCELL
  mstr_standard offpage *
  page145_i93
#ISCELL
  mstr_standard offpage *
  page145_i94
#ISCELL
  mstr_standard offpage *
  page145_i95
#ISCELL
  mstr_standard offpage *
  page145_i96
#ISCELL
  mstr_standard offpage *
  page145_i99
